FILE_TYPE = CONNECTIVITY;
{Allegro Design Entry HDL 16.6-p007 (v16-6-112F) 10/10/2012}
"PAGE_NUMBER" = 43;
0"NC";
1"M_A_ODT<3:0>";
2"M_A_ECC<7:0>";
3"M_A_CKE<3:0>";
4"M_A_DQ<63:0>";
5"M_A_MA<17:0>";
6"M_A_DQS_DN<17:0>";
7"M_A_DQS_DP<17:0>";
8"M_A_CS_N<7:0>";
9"M_A_BA<1:0>";
10"M_A_BG<1:0>";
11"M_A_CLK_DN<3:0>";
12"M_A_CLK_DP<3:0>";
13"PVDDQ_ABC\g";
14"GND\g";
15"GND\g";
16"GND\g";
17"GND\g";
18"PVPP_ABC\g";
19"PVPP_ABC\g";
20"PVTT_ABC\g";
21"P12V_NVDIMM_ABC\g";
22"M_A_MA<4>";
23"M_A_DQS_DP<11>";
24"M_A_DQS_DN<12>";
25"M_A_DQS_DP<12>";
26"M_A_DQS_DN<13>";
27"M_A_DQS_DP<13>";
28"M_A_DQS_DN<14>";
29"M_A_DQS_DP<14>";
30"M_A_DQS_DN<15>";
31"M_A_DQS_DP<15>";
32"M_A_DQS_DN<16>";
33"M_A_DQS_DP<16>";
34"M_A_DQS_DN<17>";
35"M_A_DQS_DP<9>";
36"M_A_DQS_DP<17>";
37"M_A_DQS_DN<0>";
38"M_A_DQS_DP<0>";
39"M_A_DQS_DN<1>";
40"M_A_DQS_DP<1>";
41"M_A_DQS_DP<2>";
42"M_A_DQS_DN<3>";
43"M_A_DQS_DP<3>";
44"M_A_DQS_DN<4>";
45"M_A_DQS_DP<4>";
46"M_A_DQS_DN<5>";
47"M_A_DQS_DP<5>";
48"M_A_DQS_DN<6>";
49"M_A_DQS_DP<6>";
50"M_A_DQS_DN<7>";
51"M_A_DQS_DP<7>";
52"M_A_DQS_DN<8>";
53"M_A_DQS_DP<8>";
54"M_A_DQ<61>";
55"M_A_DQ<58>";
56"M_A_DQ<56>";
57"M_A_DQ<59>";
58"M_A_DQ<60>";
59"M_A_DQ<63>";
60"M_A_DQ<62>";
61"M_A_MA<12>";
62"M_A_MA<13>";
63"M_A_MA<17>";
64"M_A_MA<11>";
65"M_A_MA<14>";
66"M_A_MA<15>";
67"M_A_MA<16>";
68"M_A_DQ<50>";
69"M_A_DQ<54>";
70"M_A_DQ<52>";
71"M_A_DQ<51>";
72"M_A_DQ<48>";
73"M_A_DQ<49>";
74"M_A_DQ<46>";
75"M_A_DQ<40>";
76"M_A_DQ<47>";
77"M_A_DQ<44>";
78"M_A_DQ<45>";
79"M_A_DQ<42>";
80"M_A_DQ<43>";
81"M_A_DQ<41>";
82"M_A_DQ<38>";
83"M_A_DQ<36>";
84"M_A_DQ<39>";
85"M_A_DQ<28>";
86"M_A_DQ<35>";
87"M_A_DQ<33>";
88"M_A_DQ<31>";
89"M_A_DQ<29>";
90"M_A_DQ<26>";
91"M_A_DQ<30>";
92"M_A_DQ<21>";
93"M_A_DQ<22>";
94"M_A_DQ<24>";
95"M_A_DQ<25>";
96"M_A_DQ<23>";
97"M_A_DQ<20>";
98"M_A_DQ<18>";
99"M_A_DQ<19>";
100"M_A_DQ<17>";
101"M_A_DQ<27>";
102"M_A_DQ<16>";
103"M_A_DQ<9>";
104"M_A_DQ<15>";
105"M_A_DQ<12>";
106"M_A_DQ<13>";
107"M_A_DQ<10>";
108"M_A_DQ<11>";
109"M_A_DQ<8>";
110"M_A_DQ<6>";
111"M_A_DQ<7>";
112"M_A_DQ<14>";
113"M_A_DQ<0>";
114"M_A_DQ<1>";
115"M_A_DQ<3>";
116"M_A_DQ<2>";
117"M_A_DQ<5>";
118"M_A_DQ<4>";
119"M_A_C<2>";
120"M_A_CLK_DP<1>";
121"M_A_CS_N<1>";
122"M_A_BA<1>";
123"M_A_CLK_DN<1>";
124"M_A_CLK_DP<0>";
125"M_A_CS_N<3>";
126"M_A_CS_N<2>";
127"M_A_MA<0>";
128"M_A_MA<1>";
129"M_A_MA<7>";
130"M_A_MA<8>";
131"M_A_ECC<7>";
132"M_A_ECC<5>";
133"M_A_ECC<2>";
134"M_A_ECC<3>";
135"M_A_ECC<0>";
136"M_A_CLK_DN<0>";
137"M_A_CKE<1>";
138"M_A_BG<0>";
139"M_A_BG<1>";
140"M_A_BA<0>";
141"M_A_MA<2>";
142"M_A_MA<10>";
143"M_A_ECC<6>";
144"M_A_PAR";
145"FM_DIMM_EVENT_COD_N";
146"M_ABC_RST_N";
147"M_A_ACT_N";
148"M_A_ALERT_N";
149"FM_ADR_COMPLETE_ABC_N";
150"SMB_DDR_ABC_VPP_SDA";
151"SMB_DDR_ABC_VPP_SCL";
152"M_A_ECC<1>";
153"TP_CH_A_DIMM_A0_RFU_2";
154"TP_CH_A_DIMM_A0_RFU_0";
155"TP_CH_A_DIMM_A0_RFU_1";
156"M_A_MA<9>";
157"M_A_DQ<55>";
158"M_A_DQS_DN<2>";
159"M_A_DQ<32>";
160"M_A_CS_N<0>";
161"M_A_VREF";
162"M_A_DQ<57>";
163"M_A_DQ<34>";
164"M_A_DQ<53>";
165"M_A_DQS_DN<9>";
166"M_A_DQS_DN<10>";
167"M_A_DQS_DP<10>";
168"M_A_DQS_DN<11>";
169"M_A_MA<6>";
170"M_A_MA<5>";
171"M_A_MA<3>";
172"M_A_DQ<37>";
173"M_A_CKE<0>";
174"M_A_ECC<4>";
175"M_A_ODT<0>";
176"M_A_ODT<1>";
%"SCONN288_H44441004"
"1","(-2400,2750)","0","mstr_sconn","I1";
;
CDS_SEC"1"
MATERIAL"SCONN"
LOCATION"J4G1"
PART_NUMBER"H44441-004"
ROOM"DDR4_CH_A"
CDS_LOCATION"J4G1"
SEC"1"
SEC_TYPE"PIP"
CDS_LIB"mstr_sconn"
BOM_COST"MEM"
PACK_TYPE"PIP";
"DQ<63>"
$PN"280"60;
"DQ<62>"
$PN"135"59;
"DQ<61>"
$PN"273"58;
"DQ<5>"
$PN"148"118;
"DQ<4>"
$PN"3"117;
"DQ<3>"
$PN"157"116;
"DQ<2>"
$PN"12"115;
"DQ<47>"
$PN"258"74;
"DQ<48>"
$PN"119"73;
"DQ<49>"
$PN"264"72;
"DQ<50>"
$PN"126"71;
"DQ<51>"
$PN"271"68;
"DQ<52>"
$PN"117"164;
"DQ<53>"
$PN"262"70;
"DQ<54>"
$PN"124"157;
"DQ<58>"
$PN"137"57;
"DQ<57>"
$PN"275"56;
"SAVE_N_NC"
$PN"230"149;
"RFU<1>"
$PN"227"155;
"RFU<0>"
$PN"205"154;
"DQ<17>"
$PN"172"102;
"DQ<15>"
$PN"166"112;
"DQ<26>"
$PN"45"101;
"DQ<27>"
$PN"190"90;
"S0_N"
$PN"84"160;
"CKE<0>"
$PN"60"173;
"ODT<1>"
$PN"91"176;
"ODT<0>"
$PN"87"175;
"CB<7>"
$PN"199"143;
"A16_RAS_N"
$PN"82"67;
"A15_CAS_N"
$PN"86"66;
"A14_WE_N"
$PN"228"65;
"A11"
$PN"210"64;
"A10"
$PN"225"142;
"DQ<38>"
$PN"102"84;
"DQ<36>"
$PN"95"172;
"DQ<35>"
$PN"249"163;
"A2"
$PN"216"141;
"ALERT_N"
$PN"208"148;
"ACT_N"
$PN"62"147;
"DQ<0>"
$PN"5"114;
"DQ<1>"
$PN"150"113;
"SA<1>"
$PN"140"16;
"SA<2>"
$PN"238"16;
"VDDSPD"
$PN"284"19;
"SA<0>"
$PN"139"16;
"BA<0>"
$PN"81"140;
"BG<1>"
$PN"207"139;
"BG<0>"
$PN"63"138;
"CK1P"
$PN"218"120;
"VREFCA"
$PN"146"161;
"SDA"
$PN"285"150;
"SCL"
$PN"141"151;
"RFU<2>"
$PN"144"153;
"RESET_N"
$PN"58"146;
"PAR"
$PN"222"144;
"EVENT_N"
$PN"78"145;
"DQ<6>"
$PN"10"111;
"DQ<7>"
$PN"155"110;
"DQ<8>"
$PN"16"103;
"DQ<9>"
$PN"161"109;
"DQ<10>"
$PN"23"108;
"DQ<11>"
$PN"168"107;
"DQ<12>"
$PN"14"106;
"DQ<13>"
$PN"159"105;
"DQ<14>"
$PN"21"104;
"DQ<16>"
$PN"27"100;
"DQ<18>"
$PN"34"99;
"DQ<19>"
$PN"179"98;
"DQ<20>"
$PN"25"92;
"DQ<21>"
$PN"170"97;
"DQ<22>"
$PN"32"96;
"DQ<23>"
$PN"177"93;
"DQ<24>"
$PN"38"95;
"DQ<25>"
$PN"183"94;
"DQ<30>"
$PN"43"88;
"DQ<31>"
$PN"188"91;
"DQ<32>"
$PN"97"87;
"DQ<33>"
$PN"242"159;
"DQ<34>"
$PN"104"86;
"DQ<37>"
$PN"240"83;
"DQ<39>"
$PN"247"82;
"DQ<40>"
$PN"108"81;
"DQ<41>"
$PN"253"75;
"DQ<42>"
$PN"115"80;
"DQ<43>"
$PN"260"79;
"DQ<44>"
$PN"106"78;
"DQ<45>"
$PN"251"77;
"DQ<46>"
$PN"113"76;
"DQ<55>"
$PN"269"69;
"DQ<56>"
$PN"130"162;
"DQ<59>"
$PN"282"55;
"DQ<60>"
$PN"128"54;
"CKE<1>"
$PN"203"137;
"CK0N"
$PN"75"136;
"CB<0>"
$PN"49"152;
"CB<1>"
$PN"194"135;
"CB<2>"
$PN"56"134;
"CB<3>"
$PN"201"133;
"CB<4>"
$PN"47"132;
"CB<5>"
$PN"192"174;
"CB<6>"
$PN"54"131;
"A9"
$PN"66"156;
"A8"
$PN"68"130;
"A7"
$PN"211"129;
"A6"
$PN"69"169;
"A5"
$PN"213"170;
"A4"
$PN"214"22;
"A3"
$PN"71"171;
"A17"
$PN"234"63;
"A13"
$PN"232"62;
"A12"
$PN"65"61;
"A1"
$PN"72"128;
"A0"
$PN"79"127;
"C<2>"
$PN"235"119;
"DQ<28>"
$PN"36"89;
"DQ<29>"
$PN"181"85;
"S1_N"
$PN"89"121;
"S2_N_C<0>"
$PN"93"126;
"S3_N_C<1>"
$PN"237"125;
"CK0P"
$PN"74"124;
"CK1N"
$PN"219"123;
"BA<1>"
$PN"224"122;
%"TAP"
"6","(-1600,4100)","2","mstr_standard","I127";
;
HDL_TAP"TRUE"
BODY_TYPE"PLUMBING"
CDS_LIB"mstr_standard";
"B \NAC \NWC"4;
"S \NAC"
BN"56"56;
%"TAP"
"6","(-1600,4150)","2","mstr_standard","I128";
;
HDL_TAP"TRUE"
BODY_TYPE"PLUMBING"
CDS_LIB"mstr_standard";
"B \NAC \NWC"4;
"S \NAC"
BN"59"57;
%"TAP"
"6","(-1600,4200)","2","mstr_standard","I129";
;
HDL_TAP"TRUE"
BODY_TYPE"PLUMBING"
CDS_LIB"mstr_standard";
"B \NAC \NWC"4;
"S \NAC"
BN"58"55;
%"TAP"
"6","(-1600,4250)","2","mstr_standard","I130";
;
HDL_TAP"TRUE"
BODY_TYPE"PLUMBING"
CDS_LIB"mstr_standard";
"B \NAC \NWC"4;
"S \NAC"
BN"61"54;
%"TAP"
"6","(-1600,4350)","2","mstr_standard","I131";
;
HDL_TAP"TRUE"
BODY_TYPE"PLUMBING"
CDS_LIB"mstr_standard";
"B \NAC \NWC"4;
"S \NAC"
BN"63"59;
%"TAP"
"6","(-1600,4300)","2","mstr_standard","I132";
;
HDL_TAP"TRUE"
BODY_TYPE"PLUMBING"
CDS_LIB"mstr_standard";
"B \NAC \NWC"4;
"S \NAC"
BN"60"58;
%"TAP"
"6","(-1600,4400)","2","mstr_standard","I133";
;
HDL_TAP"TRUE"
BODY_TYPE"PLUMBING"
CDS_LIB"mstr_standard";
"B \NAC \NWC"4;
"S \NAC"
BN"62"60;
%"TAP"
"6","(-1600,3750)","2","mstr_standard","I134";
;
HDL_TAP"TRUE"
BODY_TYPE"PLUMBING"
CDS_LIB"mstr_standard";
"B \NAC \NWC"4;
"S \NAC"
BN"51"71;
%"TAP"
"6","(-1600,3800)","2","mstr_standard","I135";
;
HDL_TAP"TRUE"
BODY_TYPE"PLUMBING"
CDS_LIB"mstr_standard";
"B \NAC \NWC"4;
"S \NAC"
BN"50"68;
%"TAP"
"6","(-1600,3900)","2","mstr_standard","I136";
;
HDL_TAP"TRUE"
BODY_TYPE"PLUMBING"
CDS_LIB"mstr_standard";
"B \NAC \NWC"4;
"S \NAC"
BN"52"70;
%"TAP"
"6","(-1600,3850)","2","mstr_standard","I137";
;
HDL_TAP"TRUE"
BODY_TYPE"PLUMBING"
CDS_LIB"mstr_standard";
"B \NAC \NWC"4;
"S \NAC"
BN"53"164;
%"TAP"
"6","(-1600,3950)","2","mstr_standard","I138";
;
HDL_TAP"TRUE"
BODY_TYPE"PLUMBING"
CDS_LIB"mstr_standard";
"B \NAC \NWC"4;
"S \NAC"
BN"55"157;
%"TAP"
"6","(-1600,4000)","2","mstr_standard","I139";
;
HDL_TAP"TRUE"
BODY_TYPE"PLUMBING"
CDS_LIB"mstr_standard";
"B \NAC \NWC"4;
"S \NAC"
BN"54"69;
%"TAP"
"6","(-1600,4050)","2","mstr_standard","I140";
;
HDL_TAP"TRUE"
BODY_TYPE"PLUMBING"
CDS_LIB"mstr_standard";
"B \NAC \NWC"4;
"S \NAC"
BN"57"162;
%"TAP"
"6","(-1600,3700)","2","mstr_standard","I141";
;
HDL_TAP"TRUE"
BODY_TYPE"PLUMBING"
CDS_LIB"mstr_standard";
"B \NAC \NWC"4;
"S \NAC"
BN"48"72;
%"TAP"
"6","(-1600,2750)","2","mstr_standard","I142";
;
HDL_TAP"TRUE"
BODY_TYPE"PLUMBING"
CDS_LIB"mstr_standard";
"B \NAC \NWC"4;
"S \NAC"
BN"31"88;
%"TAP"
"6","(-1600,2700)","2","mstr_standard","I143";
;
HDL_TAP"TRUE"
BODY_TYPE"PLUMBING"
CDS_LIB"mstr_standard";
"B \NAC \NWC"4;
"S \NAC"
BN"28"85;
%"TAP"
"6","(-1600,2800)","2","mstr_standard","I144";
;
HDL_TAP"TRUE"
BODY_TYPE"PLUMBING"
CDS_LIB"mstr_standard";
"B \NAC \NWC"4;
"S \NAC"
BN"30"91;
%"TAP"
"6","(-1600,2850)","2","mstr_standard","I145";
;
HDL_TAP"TRUE"
BODY_TYPE"PLUMBING"
CDS_LIB"mstr_standard";
"B \NAC \NWC"4;
"S \NAC"
BN"33"87;
%"TAP"
"6","(-1600,2950)","2","mstr_standard","I146";
;
HDL_TAP"TRUE"
BODY_TYPE"PLUMBING"
CDS_LIB"mstr_standard";
"B \NAC \NWC"4;
"S \NAC"
BN"35"86;
%"TAP"
"6","(-1600,2900)","2","mstr_standard","I147";
;
HDL_TAP"TRUE"
BODY_TYPE"PLUMBING"
CDS_LIB"mstr_standard";
"B \NAC \NWC"4;
"S \NAC"
BN"32"159;
%"TAP"
"6","(-1600,3000)","2","mstr_standard","I148";
;
HDL_TAP"TRUE"
BODY_TYPE"PLUMBING"
CDS_LIB"mstr_standard";
"B \NAC \NWC"4;
"S \NAC"
BN"34"163;
%"TAP"
"6","(-1600,3050)","2","mstr_standard","I149";
;
HDL_TAP"TRUE"
BODY_TYPE"PLUMBING"
CDS_LIB"mstr_standard";
"B \NAC \NWC"4;
"S \NAC"
BN"37"172;
%"TAP"
"6","(-1600,3100)","2","mstr_standard","I150";
;
HDL_TAP"TRUE"
BODY_TYPE"PLUMBING"
CDS_LIB"mstr_standard";
"B \NAC \NWC"4;
"S \NAC"
BN"36"83;
%"TAP"
"6","(-1600,3200)","2","mstr_standard","I151";
;
HDL_TAP"TRUE"
BODY_TYPE"PLUMBING"
CDS_LIB"mstr_standard";
"B \NAC \NWC"4;
"S \NAC"
BN"38"82;
%"TAP"
"6","(-1600,3150)","2","mstr_standard","I152";
;
HDL_TAP"TRUE"
BODY_TYPE"PLUMBING"
CDS_LIB"mstr_standard";
"B \NAC \NWC"4;
"S \NAC"
BN"39"84;
%"TAP"
"6","(-1600,3250)","2","mstr_standard","I153";
;
HDL_TAP"TRUE"
BODY_TYPE"PLUMBING"
CDS_LIB"mstr_standard";
"B \NAC \NWC"4;
"S \NAC"
BN"41"81;
%"TAP"
"6","(-1600,3300)","2","mstr_standard","I154";
;
HDL_TAP"TRUE"
BODY_TYPE"PLUMBING"
CDS_LIB"mstr_standard";
"B \NAC \NWC"4;
"S \NAC"
BN"40"75;
%"TAP"
"6","(-1600,3350)","2","mstr_standard","I155";
;
HDL_TAP"TRUE"
BODY_TYPE"PLUMBING"
CDS_LIB"mstr_standard";
"B \NAC \NWC"4;
"S \NAC"
BN"43"80;
%"TAP"
"6","(-1600,3450)","2","mstr_standard","I156";
;
HDL_TAP"TRUE"
BODY_TYPE"PLUMBING"
CDS_LIB"mstr_standard";
"B \NAC \NWC"4;
"S \NAC"
BN"45"78;
%"TAP"
"6","(-1600,3400)","2","mstr_standard","I157";
;
HDL_TAP"TRUE"
BODY_TYPE"PLUMBING"
CDS_LIB"mstr_standard";
"B \NAC \NWC"4;
"S \NAC"
BN"42"79;
%"TAP"
"6","(-1600,3500)","2","mstr_standard","I158";
;
HDL_TAP"TRUE"
BODY_TYPE"PLUMBING"
CDS_LIB"mstr_standard";
"B \NAC \NWC"4;
"S \NAC"
BN"44"77;
%"TAP"
"6","(-1600,3550)","2","mstr_standard","I159";
;
HDL_TAP"TRUE"
BODY_TYPE"PLUMBING"
CDS_LIB"mstr_standard";
"B \NAC \NWC"4;
"S \NAC"
BN"47"76;
%"TAP"
"6","(-1600,3650)","2","mstr_standard","I160";
;
HDL_TAP"TRUE"
BODY_TYPE"PLUMBING"
CDS_LIB"mstr_standard";
"B \NAC \NWC"4;
"S \NAC"
BN"49"73;
%"TAP"
"6","(-1600,3600)","2","mstr_standard","I161";
;
HDL_TAP"TRUE"
BODY_TYPE"PLUMBING"
CDS_LIB"mstr_standard";
"B \NAC \NWC"4;
"S \NAC"
BN"46"74;
%"TAP"
"6","(-1600,2050)","2","mstr_standard","I162";
;
HDL_TAP"TRUE"
BODY_TYPE"PLUMBING"
CDS_LIB"mstr_standard";
"B \NAC \NWC"4;
"S \NAC"
BN"17"100;
%"TAP"
"6","(-1600,2000)","2","mstr_standard","I163";
;
HDL_TAP"TRUE"
BODY_TYPE"PLUMBING"
CDS_LIB"mstr_standard";
"B \NAC \NWC"4;
"S \NAC"
BN"14"112;
%"TAP"
"6","(-1600,2100)","2","mstr_standard","I164";
;
HDL_TAP"TRUE"
BODY_TYPE"PLUMBING"
CDS_LIB"mstr_standard";
"B \NAC \NWC"4;
"S \NAC"
BN"16"102;
%"TAP"
"6","(-1600,2150)","2","mstr_standard","I165";
;
HDL_TAP"TRUE"
BODY_TYPE"PLUMBING"
CDS_LIB"mstr_standard";
"B \NAC \NWC"4;
"S \NAC"
BN"19"99;
%"TAP"
"6","(-1600,2200)","2","mstr_standard","I166";
;
HDL_TAP"TRUE"
BODY_TYPE"PLUMBING"
CDS_LIB"mstr_standard";
"B \NAC \NWC"4;
"S \NAC"
BN"18"98;
%"TAP"
"6","(-1600,2300)","2","mstr_standard","I167";
;
HDL_TAP"TRUE"
BODY_TYPE"PLUMBING"
CDS_LIB"mstr_standard";
"B \NAC \NWC"4;
"S \NAC"
BN"20"97;
%"TAP"
"6","(-1600,2250)","2","mstr_standard","I168";
;
HDL_TAP"TRUE"
BODY_TYPE"PLUMBING"
CDS_LIB"mstr_standard";
"B \NAC \NWC"4;
"S \NAC"
BN"21"92;
%"TAP"
"6","(-1600,2350)","2","mstr_standard","I169";
;
HDL_TAP"TRUE"
BODY_TYPE"PLUMBING"
CDS_LIB"mstr_standard";
"B \NAC \NWC"4;
"S \NAC"
BN"23"96;
%"TAP"
"6","(-1600,2400)","2","mstr_standard","I170";
;
HDL_TAP"TRUE"
BODY_TYPE"PLUMBING"
CDS_LIB"mstr_standard";
"B \NAC \NWC"4;
"S \NAC"
BN"22"93;
%"TAP"
"6","(-1600,2500)","2","mstr_standard","I171";
;
HDL_TAP"TRUE"
BODY_TYPE"PLUMBING"
CDS_LIB"mstr_standard";
"B \NAC \NWC"4;
"S \NAC"
BN"24"94;
%"TAP"
"6","(-1600,2450)","2","mstr_standard","I172";
;
HDL_TAP"TRUE"
BODY_TYPE"PLUMBING"
CDS_LIB"mstr_standard";
"B \NAC \NWC"4;
"S \NAC"
BN"25"95;
%"TAP"
"6","(-1600,2550)","2","mstr_standard","I173";
;
HDL_TAP"TRUE"
BODY_TYPE"PLUMBING"
CDS_LIB"mstr_standard";
"B \NAC \NWC"4;
"S \NAC"
BN"27"101;
%"TAP"
"6","(-1600,2600)","2","mstr_standard","I174";
;
HDL_TAP"TRUE"
BODY_TYPE"PLUMBING"
CDS_LIB"mstr_standard";
"B \NAC \NWC"4;
"S \NAC"
BN"26"90;
%"TAP"
"6","(-1600,2650)","2","mstr_standard","I175";
;
HDL_TAP"TRUE"
BODY_TYPE"PLUMBING"
CDS_LIB"mstr_standard";
"B \NAC \NWC"4;
"S \NAC"
BN"29"89;
%"TAP"
"6","(-1600,1700)","2","mstr_standard","I176";
;
HDL_TAP"TRUE"
BODY_TYPE"PLUMBING"
CDS_LIB"mstr_standard";
"B \NAC \NWC"4;
"S \NAC"
BN"8"109;
%"TAP"
"6","(-1600,1750)","2","mstr_standard","I177";
;
HDL_TAP"TRUE"
BODY_TYPE"PLUMBING"
CDS_LIB"mstr_standard";
"B \NAC \NWC"4;
"S \NAC"
BN"11"108;
%"TAP"
"6","(-1600,1850)","2","mstr_standard","I178";
;
HDL_TAP"TRUE"
BODY_TYPE"PLUMBING"
CDS_LIB"mstr_standard";
"B \NAC \NWC"4;
"S \NAC"
BN"13"106;
%"TAP"
"6","(-1600,1800)","2","mstr_standard","I179";
;
HDL_TAP"TRUE"
BODY_TYPE"PLUMBING"
CDS_LIB"mstr_standard";
"B \NAC \NWC"4;
"S \NAC"
BN"10"107;
%"TAP"
"6","(-1600,1900)","2","mstr_standard","I180";
;
HDL_TAP"TRUE"
BODY_TYPE"PLUMBING"
CDS_LIB"mstr_standard";
"B \NAC \NWC"4;
"S \NAC"
BN"12"105;
%"TAP"
"6","(-1600,1950)","2","mstr_standard","I181";
;
HDL_TAP"TRUE"
BODY_TYPE"PLUMBING"
CDS_LIB"mstr_standard";
"B \NAC \NWC"4;
"S \NAC"
BN"15"104;
%"TAP"
"6","(-1600,1650)","2","mstr_standard","I182";
;
HDL_TAP"TRUE"
BODY_TYPE"PLUMBING"
CDS_LIB"mstr_standard";
"B \NAC \NWC"4;
"S \NAC"
BN"9"103;
%"TAP"
"6","(-1600,1250)","2","mstr_standard","I183";
;
HDL_TAP"TRUE"
BODY_TYPE"PLUMBING"
CDS_LIB"mstr_standard";
"B \NAC \NWC"4;
"S \NAC"
BN"1"114;
%"TAP"
"6","(-1600,1350)","2","mstr_standard","I184";
;
HDL_TAP"TRUE"
BODY_TYPE"PLUMBING"
CDS_LIB"mstr_standard";
"B \NAC \NWC"4;
"S \NAC"
BN"3"115;
%"TAP"
"6","(-1600,1300)","2","mstr_standard","I185";
;
HDL_TAP"TRUE"
BODY_TYPE"PLUMBING"
CDS_LIB"mstr_standard";
"B \NAC \NWC"4;
"S \NAC"
BN"0"113;
%"TAP"
"6","(-1600,1400)","2","mstr_standard","I186";
;
HDL_TAP"TRUE"
BODY_TYPE"PLUMBING"
CDS_LIB"mstr_standard";
"B \NAC \NWC"4;
"S \NAC"
BN"2"116;
%"TAP"
"6","(-1600,1450)","2","mstr_standard","I187";
;
HDL_TAP"TRUE"
BODY_TYPE"PLUMBING"
CDS_LIB"mstr_standard";
"B \NAC \NWC"4;
"S \NAC"
BN"5"117;
%"TAP"
"6","(-1600,1500)","2","mstr_standard","I188";
;
HDL_TAP"TRUE"
BODY_TYPE"PLUMBING"
CDS_LIB"mstr_standard";
"B \NAC \NWC"4;
"S \NAC"
BN"4"118;
%"TAP"
"6","(-1600,1600)","2","mstr_standard","I189";
;
HDL_TAP"TRUE"
BODY_TYPE"PLUMBING"
CDS_LIB"mstr_standard";
"B \NAC \NWC"4;
"S \NAC"
BN"6"110;
%"TAP"
"6","(-1600,1550)","2","mstr_standard","I190";
;
HDL_TAP"TRUE"
BODY_TYPE"PLUMBING"
CDS_LIB"mstr_standard";
"B \NAC \NWC"4;
"S \NAC"
BN"7"111;
%"TAP"
"6","(650,4200)","2","mstr_standard","I192";
;
HDL_TAP"TRUE"
BODY_TYPE"PLUMBING"
CDS_LIB"mstr_standard";
"B \NAC \NWC"7;
"S \NAC"
BN"10"167;
%"TAP"
"6","(650,4300)","2","mstr_standard","I193";
;
HDL_TAP"TRUE"
BODY_TYPE"PLUMBING"
CDS_LIB"mstr_standard";
"B \NAC \NWC"7;
"S \NAC"
BN"11"23;
%"TAP"
"6","(650,4000)","2","mstr_standard","I194";
;
HDL_TAP"TRUE"
BODY_TYPE"PLUMBING"
CDS_LIB"mstr_standard";
"B \NAC \NWC"7;
"S \NAC"
BN"8"53;
%"TAP"
"6","(650,4100)","2","mstr_standard","I195";
;
HDL_TAP"TRUE"
BODY_TYPE"PLUMBING"
CDS_LIB"mstr_standard";
"B \NAC \NWC"7;
"S \NAC"
BN"9"35;
%"TAP"
"6","(650,3700)","2","mstr_standard","I196";
;
HDL_TAP"TRUE"
BODY_TYPE"PLUMBING"
CDS_LIB"mstr_standard";
"B \NAC \NWC"7;
"S \NAC"
BN"5"47;
%"TAP"
"6","(650,3800)","2","mstr_standard","I197";
;
HDL_TAP"TRUE"
BODY_TYPE"PLUMBING"
CDS_LIB"mstr_standard";
"B \NAC \NWC"7;
"S \NAC"
BN"6"49;
%"TAP"
"6","(650,3900)","2","mstr_standard","I198";
;
HDL_TAP"TRUE"
BODY_TYPE"PLUMBING"
CDS_LIB"mstr_standard";
"B \NAC \NWC"7;
"S \NAC"
BN"7"51;
%"TAP"
"6","(650,3500)","2","mstr_standard","I199";
;
HDL_TAP"TRUE"
BODY_TYPE"PLUMBING"
CDS_LIB"mstr_standard";
"B \NAC \NWC"7;
"S \NAC"
BN"3"43;
%"SCONN288_H44441004"
"2","(-50,4050)","0","mstr_sconn","I2";
;
CDS_SEC"2"
MATERIAL"SCONN"
PART_NUMBER"H44441-004"
LOCATION"J4G1"
ROOM"DDR4_CH_A"
CDS_LOCATION"J4G1"
SEC"2"
SEC_TYPE"PIP"
CDS_LIB"mstr_sconn"
BOM_COST"MEM"
PACK_TYPE"PIP";
"DQS17P"
$PN"51"36;
"DQS9P"
$PN"7"35;
"DQS9N"
$PN"8"165;
"DQS8P"
$PN"197"53;
"DQS8N"
$PN"196"52;
"DQS7P"
$PN"278"51;
"DQS7N"
$PN"277"50;
"DQS6P"
$PN"267"49;
"DQS6N"
$PN"266"48;
"DQS5P"
$PN"256"47;
"DQS5N"
$PN"255"46;
"DQS4P"
$PN"245"45;
"DQS4N"
$PN"244"44;
"DQS3P"
$PN"186"43;
"DQS3N"
$PN"185"42;
"DQS2P"
$PN"175"41;
"DQS2N"
$PN"174"158;
"DQS1P"
$PN"164"40;
"DQS1N"
$PN"163"39;
"DQS17N"
$PN"52"34;
"DQS16P"
$PN"132"33;
"DQS16N"
$PN"133"32;
"DQS15P"
$PN"121"31;
"DQS15N"
$PN"122"30;
"DQS14P"
$PN"110"29;
"DQS14N"
$PN"111"28;
"DQS13P"
$PN"99"27;
"DQS13N"
$PN"100"26;
"DQS12P"
$PN"40"25;
"DQS12N"
$PN"41"24;
"DQS11P"
$PN"29"23;
"DQS11N"
$PN"30"168;
"DQS10P"
$PN"18"167;
"DQS10N"
$PN"19"166;
"DQS0P"
$PN"153"38;
"DQS0N"
$PN"152"37;
%"TAP"
"6","(650,3600)","2","mstr_standard","I200";
;
HDL_TAP"TRUE"
BODY_TYPE"PLUMBING"
CDS_LIB"mstr_standard";
"B \NAC \NWC"7;
"S \NAC"
BN"4"45;
%"TAP"
"6","(650,3200)","2","mstr_standard","I201";
;
HDL_TAP"TRUE"
BODY_TYPE"PLUMBING"
CDS_LIB"mstr_standard";
"B \NAC \NWC"7;
"S \NAC"
BN"0"38;
%"TAP"
"6","(650,3300)","2","mstr_standard","I202";
;
HDL_TAP"TRUE"
BODY_TYPE"PLUMBING"
CDS_LIB"mstr_standard";
"B \NAC \NWC"7;
"S \NAC"
BN"1"40;
%"TAP"
"6","(650,3400)","2","mstr_standard","I203";
;
HDL_TAP"TRUE"
BODY_TYPE"PLUMBING"
CDS_LIB"mstr_standard";
"B \NAC \NWC"7;
"S \NAC"
BN"2"41;
%"TAP"
"6","(650,4700)","2","mstr_standard","I205";
;
HDL_TAP"TRUE"
BODY_TYPE"PLUMBING"
CDS_LIB"mstr_standard";
"B \NAC \NWC"7;
"S \NAC"
BN"15"31;
%"TAP"
"6","(650,4900)","2","mstr_standard","I206";
;
HDL_TAP"TRUE"
BODY_TYPE"PLUMBING"
CDS_LIB"mstr_standard";
"B \NAC \NWC"7;
"S \NAC"
BN"17"36;
%"TAP"
"6","(650,4800)","2","mstr_standard","I207";
;
HDL_TAP"TRUE"
BODY_TYPE"PLUMBING"
CDS_LIB"mstr_standard";
"B \NAC \NWC"7;
"S \NAC"
BN"16"33;
%"TAP"
"6","(650,4500)","2","mstr_standard","I208";
;
HDL_TAP"TRUE"
BODY_TYPE"PLUMBING"
CDS_LIB"mstr_standard";
"B \NAC \NWC"7;
"S \NAC"
BN"13"27;
%"TAP"
"6","(650,4600)","2","mstr_standard","I209";
;
HDL_TAP"TRUE"
BODY_TYPE"PLUMBING"
CDS_LIB"mstr_standard";
"B \NAC \NWC"7;
"S \NAC"
BN"14"29;
%"TAP"
"6","(650,4400)","2","mstr_standard","I210";
;
HDL_TAP"TRUE"
BODY_TYPE"PLUMBING"
CDS_LIB"mstr_standard";
"B \NAC \NWC"7;
"S \NAC"
BN"12"25;
%"TAP"
"6","(850,4850)","2","mstr_standard","I212";
;
HDL_TAP"TRUE"
BODY_TYPE"PLUMBING"
CDS_LIB"mstr_standard";
"B \NAC \NWC"6;
"S \NAC"
BN"17"34;
%"TAP"
"6","(850,4750)","2","mstr_standard","I213";
;
HDL_TAP"TRUE"
BODY_TYPE"PLUMBING"
CDS_LIB"mstr_standard";
"B \NAC \NWC"6;
"S \NAC"
BN"16"32;
%"TAP"
"6","(850,4650)","2","mstr_standard","I214";
;
HDL_TAP"TRUE"
BODY_TYPE"PLUMBING"
CDS_LIB"mstr_standard";
"B \NAC \NWC"6;
"S \NAC"
BN"15"30;
%"TAP"
"6","(850,4550)","2","mstr_standard","I215";
;
HDL_TAP"TRUE"
BODY_TYPE"PLUMBING"
CDS_LIB"mstr_standard";
"B \NAC \NWC"6;
"S \NAC"
BN"14"28;
%"TAP"
"6","(850,4450)","2","mstr_standard","I216";
;
HDL_TAP"TRUE"
BODY_TYPE"PLUMBING"
CDS_LIB"mstr_standard";
"B \NAC \NWC"6;
"S \NAC"
BN"13"26;
%"TAP"
"6","(850,4350)","2","mstr_standard","I217";
;
HDL_TAP"TRUE"
BODY_TYPE"PLUMBING"
CDS_LIB"mstr_standard";
"B \NAC \NWC"6;
"S \NAC"
BN"12"24;
%"TAP"
"6","(850,4250)","2","mstr_standard","I218";
;
HDL_TAP"TRUE"
BODY_TYPE"PLUMBING"
CDS_LIB"mstr_standard";
"B \NAC \NWC"6;
"S \NAC"
BN"11"168;
%"TAP"
"6","(850,4150)","2","mstr_standard","I219";
;
HDL_TAP"TRUE"
BODY_TYPE"PLUMBING"
CDS_LIB"mstr_standard";
"B \NAC \NWC"6;
"S \NAC"
BN"10"166;
%"TAP"
"6","(-3150,4400)","0","mstr_standard","I22";
;
HDL_TAP"TRUE"
BODY_TYPE"PLUMBING"
CDS_LIB"mstr_standard";
"B \NAC \NWC"5;
"S \NAC"
BN"17"63;
%"TAP"
"6","(850,4050)","2","mstr_standard","I220";
;
HDL_TAP"TRUE"
BODY_TYPE"PLUMBING"
CDS_LIB"mstr_standard";
"B \NAC \NWC"6;
"S \NAC"
BN"9"165;
%"TAP"
"6","(850,3950)","2","mstr_standard","I221";
;
HDL_TAP"TRUE"
BODY_TYPE"PLUMBING"
CDS_LIB"mstr_standard";
"B \NAC \NWC"6;
"S \NAC"
BN"8"52;
%"TAP"
"6","(850,3850)","2","mstr_standard","I222";
;
HDL_TAP"TRUE"
BODY_TYPE"PLUMBING"
CDS_LIB"mstr_standard";
"B \NAC \NWC"6;
"S \NAC"
BN"7"50;
%"TAP"
"6","(850,3750)","2","mstr_standard","I223";
;
HDL_TAP"TRUE"
BODY_TYPE"PLUMBING"
CDS_LIB"mstr_standard";
"B \NAC \NWC"6;
"S \NAC"
BN"6"48;
%"TAP"
"6","(850,3650)","2","mstr_standard","I224";
;
HDL_TAP"TRUE"
BODY_TYPE"PLUMBING"
CDS_LIB"mstr_standard";
"B \NAC \NWC"6;
"S \NAC"
BN"5"46;
%"TAP"
"6","(850,3550)","2","mstr_standard","I225";
;
HDL_TAP"TRUE"
BODY_TYPE"PLUMBING"
CDS_LIB"mstr_standard";
"B \NAC \NWC"6;
"S \NAC"
BN"4"44;
%"TAP"
"6","(850,3450)","2","mstr_standard","I226";
;
HDL_TAP"TRUE"
BODY_TYPE"PLUMBING"
CDS_LIB"mstr_standard";
"B \NAC \NWC"6;
"S \NAC"
BN"3"42;
%"TAP"
"6","(850,3350)","2","mstr_standard","I227";
;
HDL_TAP"TRUE"
BODY_TYPE"PLUMBING"
CDS_LIB"mstr_standard";
"B \NAC \NWC"6;
"S \NAC"
BN"2"158;
%"TAP"
"6","(850,3250)","2","mstr_standard","I228";
;
HDL_TAP"TRUE"
BODY_TYPE"PLUMBING"
CDS_LIB"mstr_standard";
"B \NAC \NWC"6;
"S \NAC"
BN"1"39;
%"TAP"
"6","(850,3150)","2","mstr_standard","I229";
;
HDL_TAP"TRUE"
BODY_TYPE"PLUMBING"
CDS_LIB"mstr_standard";
"B \NAC \NWC"6;
"S \NAC"
BN"0"37;
%"TAP"
"6","(-3150,4350)","0","mstr_standard","I23";
;
HDL_TAP"TRUE"
BODY_TYPE"PLUMBING"
CDS_LIB"mstr_standard";
"B \NAC \NWC"5;
"S \NAC"
BN"16"67;
%"TAP"
"6","(-3150,2450)","0","mstr_standard","I235";
;
HDL_TAP"TRUE"
BODY_TYPE"PLUMBING"
CDS_LIB"mstr_standard";
"B \NAC \NWC"1;
"S \NAC"
BN"0"175;
%"TAP"
"6","(-3150,2500)","0","mstr_standard","I236";
;
HDL_TAP"TRUE"
BODY_TYPE"PLUMBING"
CDS_LIB"mstr_standard";
"B \NAC \NWC"1;
"S \NAC"
BN"1"176;
%"TAP"
"6","(-3150,2650)","0","mstr_standard","I238";
;
HDL_TAP"TRUE"
BODY_TYPE"PLUMBING"
CDS_LIB"mstr_standard";
"B \NAC \NWC"3;
"S \NAC"
BN"1"137;
%"TAP"
"6","(-3150,2600)","0","mstr_standard","I239";
;
HDL_TAP"TRUE"
BODY_TYPE"PLUMBING"
CDS_LIB"mstr_standard";
"B \NAC \NWC"3;
"S \NAC"
BN"0"173;
%"TAP"
"6","(-3150,4300)","0","mstr_standard","I24";
;
HDL_TAP"TRUE"
BODY_TYPE"PLUMBING"
CDS_LIB"mstr_standard";
"B \NAC \NWC"5;
"S \NAC"
BN"15"66;
%"TAP"
"6","(-3150,2900)","0","mstr_standard","I241";
;
HDL_TAP"TRUE"
BODY_TYPE"PLUMBING"
CDS_LIB"mstr_standard";
"B \NAC \NWC"8;
"S \NAC"
BN"3"125;
%"TAP"
"6","(-3150,2850)","0","mstr_standard","I242";
;
HDL_TAP"TRUE"
BODY_TYPE"PLUMBING"
CDS_LIB"mstr_standard";
"B \NAC \NWC"8;
"S \NAC"
BN"2"126;
%"TAP"
"6","(-3150,2800)","0","mstr_standard","I243";
;
HDL_TAP"TRUE"
BODY_TYPE"PLUMBING"
CDS_LIB"mstr_standard";
"B \NAC \NWC"8;
"S \NAC"
BN"1"121;
%"TAP"
"6","(-3150,2750)","0","mstr_standard","I244";
;
HDL_TAP"TRUE"
BODY_TYPE"PLUMBING"
CDS_LIB"mstr_standard";
"B \NAC \NWC"8;
"S \NAC"
BN"0"160;
%"TAP"
"6","(-3350,3050)","0","mstr_standard","I247";
;
HDL_TAP"TRUE"
BODY_TYPE"PLUMBING"
CDS_LIB"mstr_standard";
"B \NAC \NWC"11;
"S \NAC"
BN"0"136;
%"TAP"
"6","(-3150,4250)","0","mstr_standard","I25";
;
HDL_TAP"TRUE"
BODY_TYPE"PLUMBING"
CDS_LIB"mstr_standard";
"B \NAC \NWC"5;
"S \NAC"
BN"14"65;
%"TAP"
"6","(-3150,3200)","0","mstr_standard","I250";
;
HDL_TAP"TRUE"
BODY_TYPE"PLUMBING"
CDS_LIB"mstr_standard";
"B \NAC \NWC"12;
"S \NAC"
BN"1"120;
%"TAP"
"6","(-3150,3100)","0","mstr_standard","I252";
;
HDL_TAP"TRUE"
BODY_TYPE"PLUMBING"
CDS_LIB"mstr_standard";
"B \NAC \NWC"12;
"S \NAC"
BN"0"124;
%"TAP"
"6","(-3350,3150)","0","mstr_standard","I254";
;
HDL_TAP"TRUE"
BODY_TYPE"PLUMBING"
CDS_LIB"mstr_standard";
"B \NAC \NWC"11;
"S \NAC"
BN"1"123;
%"SCONN288_H44441004"
"3","(1750,2450)","0","mstr_sconn","I259";
;
CDS_SEC"3"
MATERIAL"SCONN"
PART_NUMBER"H44441-004"
LOCATION"J4G1"
ROOM"DDR4_CH_A"
CDS_LOCATION"J4G1"
SEC"3"
SEC_TYPE"PIP"
CDS_LIB"mstr_sconn"
BOM_COST"MEM"
PACK_TYPE"PIP";
"VSS<93>"
$PN"2"14;
"VSS<92>"
$PN"4"14;
"VSS<91>"
$PN"6"14;
"VSS<90>"
$PN"9"14;
"VSS<89>"
$PN"11"14;
"VSS<88>"
$PN"13"14;
"VSS<0>"
$PN"283"15;
"VSS<1>"
$PN"281"15;
"VSS<2>"
$PN"279"15;
"VSS<3>"
$PN"276"15;
"VSS<4>"
$PN"274"15;
"VSS<5>"
$PN"272"15;
"VSS<6>"
$PN"270"15;
"VSS<7>"
$PN"268"15;
"VSS<8>"
$PN"265"15;
"VSS<9>"
$PN"263"15;
"VSS<10>"
$PN"261"15;
"VSS<11>"
$PN"259"15;
"VSS<12>"
$PN"257"15;
"VSS<13>"
$PN"254"15;
"VSS<14>"
$PN"252"15;
"VSS<15>"
$PN"250"15;
"VSS<16>"
$PN"248"15;
"VSS<17>"
$PN"246"15;
"VSS<18>"
$PN"243"15;
"VSS<19>"
$PN"241"15;
"VSS<20>"
$PN"239"15;
"VSS<21>"
$PN"202"15;
"VSS<22>"
$PN"200"15;
"VSS<23>"
$PN"198"15;
"VSS<24>"
$PN"195"15;
"VSS<25>"
$PN"193"15;
"VSS<26>"
$PN"191"15;
"VSS<27>"
$PN"189"15;
"VSS<28>"
$PN"187"15;
"VSS<29>"
$PN"184"15;
"VSS<30>"
$PN"182"15;
"VSS<31>"
$PN"180"15;
"VSS<32>"
$PN"178"15;
"VSS<33>"
$PN"176"15;
"VSS<34>"
$PN"173"15;
"VSS<35>"
$PN"171"15;
"VSS<36>"
$PN"169"15;
"VSS<37>"
$PN"167"15;
"VSS<38>"
$PN"165"15;
"VSS<39>"
$PN"162"15;
"VSS<40>"
$PN"160"15;
"VSS<41>"
$PN"158"15;
"VSS<42>"
$PN"156"15;
"VSS<43>"
$PN"154"15;
"VSS<44>"
$PN"151"15;
"VSS<47>"
$PN"138"14;
"VSS<48>"
$PN"136"14;
"VSS<49>"
$PN"134"14;
"VSS<50>"
$PN"131"14;
"VSS<51>"
$PN"129"14;
"VSS<52>"
$PN"127"14;
"VSS<53>"
$PN"125"14;
"VSS<54>"
$PN"123"14;
"VSS<55>"
$PN"120"14;
"VSS<56>"
$PN"118"14;
"VSS<57>"
$PN"116"14;
"VSS<58>"
$PN"114"14;
"VSS<59>"
$PN"112"14;
"VSS<60>"
$PN"109"14;
"VSS<61>"
$PN"107"14;
"VSS<62>"
$PN"105"14;
"VSS<63>"
$PN"103"14;
"VSS<64>"
$PN"101"14;
"VSS<65>"
$PN"98"14;
"VSS<66>"
$PN"96"14;
"VSS<67>"
$PN"94"14;
"VSS<68>"
$PN"57"14;
"VSS<69>"
$PN"55"14;
"VSS<70>"
$PN"53"14;
"VSS<71>"
$PN"50"14;
"VSS<72>"
$PN"48"14;
"VSS<73>"
$PN"46"14;
"VSS<74>"
$PN"44"14;
"VSS<75>"
$PN"42"14;
"VSS<76>"
$PN"39"14;
"VSS<77>"
$PN"37"14;
"VSS<78>"
$PN"35"14;
"VSS<79>"
$PN"33"14;
"VSS<80>"
$PN"31"14;
"VSS<81>"
$PN"28"14;
"VSS<82>"
$PN"26"14;
"VSS<83>"
$PN"24"14;
"VSS<84>"
$PN"22"14;
"VSS<85>"
$PN"20"14;
"VSS<86>"
$PN"17"14;
"VSS<87>"
$PN"15"14;
"VSS<45>"
$PN"149"15;
"VSS<46>"
$PN"147"15;
%"TAP"
"6","(-3150,4200)","0","mstr_standard","I26";
;
HDL_TAP"TRUE"
BODY_TYPE"PLUMBING"
CDS_LIB"mstr_standard";
"B \NAC \NWC"5;
"S \NAC"
BN"13"62;
%"SCONN288_H44441004"
"4","(-100,1700)","0","mstr_sconn","I260";
;
CDS_SEC"4"
MATERIAL"SCONN"
PART_NUMBER"H44441-004"
LOCATION"J4G1"
ROOM"DDR4_CH_A"
CDS_LOCATION"J4G1"
SEC"4"
SEC_TYPE"PIP"
CDS_LIB"mstr_sconn"
BOM_COST"MEM"
PACK_TYPE"PIP";
"VPP<4>"
$PN"142"18;
"VTT<1>"
$PN"77"20;
"VPP<0>"
$PN"287"18;
"VPP<1>"
$PN"286"18;
"VPP<2>"
$PN"288"18;
"VPP<3>"
$PN"143"18;
"VDD<1>"
$PN"233"13;
"VDD<2>"
$PN"231"13;
"VDD<3>"
$PN"229"13;
"VDD<4>"
$PN"226"13;
"VDD<5>"
$PN"223"13;
"VDD<7>"
$PN"217"13;
"VDD<8>"
$PN"215"13;
"VDD<9>"
$PN"212"13;
"VDD<11>"
$PN"206"13;
"VDD<12>"
$PN"204"13;
"VDD<14>"
$PN"90"13;
"VDD<15>"
$PN"88"13;
"VDD<17>"
$PN"83"13;
"VDD<18>"
$PN"80"13;
"VDD<20>"
$PN"73"13;
"VDD<21>"
$PN"70"13;
"VDD<22>"
$PN"67"13;
"VDD<24>"
$PN"61"13;
"12V<0>"
$PN"145"21;
"12V<1>"
$PN"1"21;
"VTT<0>"
$PN"221"20;
"VDD<25>"
$PN"59"13;
"VDD<23>"
$PN"64"13;
"VDD<19>"
$PN"76"13;
"VDD<16>"
$PN"85"13;
"VDD<13>"
$PN"92"13;
"VDD<10>"
$PN"209"13;
"VDD<6>"
$PN"220"13;
"VDD<0>"
$PN"236"13;
%"PVDDQ_ABC"
"1","(-1125,2250)","0","mstr_symbols","I263";
;
HDL_POWER"PVDDQ_ABC"
ROOM"DDR4_CH_A"
BODY_TYPE"PLUMBING"
CDS_LIB"mstr_symbols"
BOM_COST"MEM"
VOLTAGE"1.2V";
"G\NAC"13;
%"GND"
"1","(1050,1150)","2","mstr_symbols","I264";
;
HDL_POWER"GND"
ROOM"DDR4_CH_A"
BODY_TYPE"PLUMBING"
BOM_COST"MEM"
CDS_LIB"mstr_symbols"
SIZE"1B"
VOLTAGE"0";
"A\NAC"14;
%"GND"
"1","(2450,1150)","2","mstr_symbols","I265";
;
HDL_POWER"GND"
ROOM"DDR4_CH_A"
BODY_TYPE"PLUMBING"
SIZE"1B"
BOM_COST"MEM"
CDS_LIB"mstr_symbols"
VOLTAGE"0";
"A\NAC"15;
%"GND"
"1","(-5050,1400)","2","mstr_symbols","I267";
;
HDL_POWER"GND"
ROOM"DDR4_CH_A"
BODY_TYPE"PLUMBING"
SIZE"1B"
CDS_LIB"mstr_symbols"
BOM_COST"MEM"
VOLTAGE"0";
"A\NAC"16;
%"TAP"
"6","(-3150,4150)","0","mstr_standard","I27";
;
HDL_TAP"TRUE"
BODY_TYPE"PLUMBING"
CDS_LIB"mstr_standard";
"B \NAC \NWC"5;
"S \NAC"
BN"12"61;
%"GND"
"1","(-4350,800)","0","mstr_symbols","I271";
;
HDL_POWER"GND"
ROOM"DDR4_CH_A"
BODY_TYPE"PLUMBING"
BOM_COST"MEM"
CDS_LIB"mstr_symbols"
SIZE"1B"
VOLTAGE"0";
"A\NAC"17;
%"CAP_A"
"1","(-4350,1050)","2","dev_discrete","I272";
;
CDS_SEC"1"
PACK_TYPE"0402V"
LOCATION"C4F10"
PART_NUMBER"A36096-045"
VALUE"0.01UF"
TOLERANCE"10%"
VOLTAGE"25V"
MATERIAL"X7R"
SEC"1"
SEC_TYPE"0402V"
CDS_LOCATION"C4F10"
BOM_COST"MEM"
CDS_LIB"dev_discrete"
ROOM"DDR4_CH_A";
"B"
$PN"2"17;
"A"
$PN"1"161;
%"PVPP_ABC"
"1","(-750,2700)","0","mstr_symbols","I273";
;
HDL_POWER"PVPP_ABC"
ROOM"DDR4_CH_A"
BODY_TYPE"PLUMBING"
CDS_LIB"mstr_symbols"
BOM_COST"MEM"
VOLTAGE"2.5V";
"G\NAC"18;
%"PVPP_ABC"
"1","(-5050,1750)","0","mstr_symbols","I274";
;
HDL_POWER"PVPP_ABC"
ROOM"DDR4_CH_A"
BODY_TYPE"PLUMBING"
CDS_LIB"mstr_symbols"
BOM_COST"MEM"
VOLTAGE"2.5V";
"G\NAC"19;
%"PVTT_ABC"
"1","(-900,2400)","0","mstr_symbols","I275";
;
HDL_POWER"PVTT_ABC"
ROOM"DDR4_CH_A"
BODY_TYPE"PLUMBING"
CDS_LIB"mstr_symbols"
BOM_COST"MEM"
VOLTAGE"0.6V";
"G\NAC"20;
%"TAP"
"6","(-3150,4100)","0","mstr_standard","I28";
;
HDL_TAP"TRUE"
BODY_TYPE"PLUMBING"
CDS_LIB"mstr_standard";
"B \NAC \NWC"5;
"S \NAC"
BN"11"64;
%"P12V_NVDIMM_ABC"
"1","(600,2775)","0","mstr_symbols","I289";
;
HDL_POWER"P12V_NVDIMM_ABC"
BODY_TYPE"PLUMBING"
CDS_LIB"mstr_symbols"
VOLTAGE"12.0";
"G\NAC"21;
%"TAP"
"6","(-3150,4050)","0","mstr_standard","I29";
;
HDL_TAP"TRUE"
BODY_TYPE"PLUMBING"
CDS_LIB"mstr_standard";
"B \NAC \NWC"5;
"S \NAC"
BN"10"142;
%"TAP"
"6","(-3150,4000)","0","mstr_standard","I30";
;
HDL_TAP"TRUE"
BODY_TYPE"PLUMBING"
CDS_LIB"mstr_standard";
"B \NAC \NWC"5;
"S \NAC"
BN"9"156;
%"TAP"
"6","(-3150,3950)","0","mstr_standard","I31";
;
HDL_TAP"TRUE"
BODY_TYPE"PLUMBING"
CDS_LIB"mstr_standard";
"B \NAC \NWC"5;
"S \NAC"
BN"8"130;
%"TAP"
"6","(-3150,3850)","0","mstr_standard","I32";
;
HDL_TAP"TRUE"
BODY_TYPE"PLUMBING"
CDS_LIB"mstr_standard";
"B \NAC \NWC"5;
"S \NAC"
BN"6"169;
%"TAP"
"6","(-3150,3900)","0","mstr_standard","I33";
;
HDL_TAP"TRUE"
BODY_TYPE"PLUMBING"
CDS_LIB"mstr_standard";
"B \NAC \NWC"5;
"S \NAC"
BN"7"129;
%"TAP"
"6","(-3150,3800)","0","mstr_standard","I34";
;
HDL_TAP"TRUE"
BODY_TYPE"PLUMBING"
CDS_LIB"mstr_standard";
"B \NAC \NWC"5;
"S \NAC"
BN"5"170;
%"TAP"
"6","(-3150,3700)","0","mstr_standard","I35";
;
HDL_TAP"TRUE"
BODY_TYPE"PLUMBING"
CDS_LIB"mstr_standard";
"B \NAC \NWC"5;
"S \NAC"
BN"3"171;
%"TAP"
"6","(-3150,3750)","0","mstr_standard","I36";
;
HDL_TAP"TRUE"
BODY_TYPE"PLUMBING"
CDS_LIB"mstr_standard";
"B \NAC \NWC"5;
"S \NAC"
BN"4"22;
%"TAP"
"6","(-3150,3650)","0","mstr_standard","I37";
;
HDL_TAP"TRUE"
BODY_TYPE"PLUMBING"
CDS_LIB"mstr_standard";
"B \NAC \NWC"5;
"S \NAC"
BN"2"141;
%"TAP"
"6","(-3150,3600)","0","mstr_standard","I38";
;
HDL_TAP"TRUE"
BODY_TYPE"PLUMBING"
CDS_LIB"mstr_standard";
"B \NAC \NWC"5;
"S \NAC"
BN"1"128;
%"TAP"
"6","(-3150,3550)","0","mstr_standard","I39";
;
HDL_TAP"TRUE"
BODY_TYPE"PLUMBING"
CDS_LIB"mstr_standard";
"B \NAC \NWC"5;
"S \NAC"
BN"0"127;
%"TAP"
"6","(-3150,3300)","0","mstr_standard","I43";
;
HDL_TAP"TRUE"
BODY_TYPE"PLUMBING"
CDS_LIB"mstr_standard";
"B \NAC \NWC"10;
"S \NAC"
BN"0"138;
%"TAP"
"6","(-3150,3350)","0","mstr_standard","I44";
;
HDL_TAP"TRUE"
BODY_TYPE"PLUMBING"
CDS_LIB"mstr_standard";
"B \NAC \NWC"10;
"S \NAC"
BN"1"139;
%"TAP"
"6","(-3150,3450)","0","mstr_standard","I45";
;
HDL_TAP"TRUE"
BODY_TYPE"PLUMBING"
CDS_LIB"mstr_standard";
"B \NAC \NWC"9;
"S \NAC"
BN"1"122;
%"TAP"
"6","(-3150,3400)","0","mstr_standard","I46";
;
HDL_TAP"TRUE"
BODY_TYPE"PLUMBING"
CDS_LIB"mstr_standard";
"B \NAC \NWC"9;
"S \NAC"
BN"0"140;
%"TAP"
"6","(-3150,2350)","0","mstr_standard","I49";
;
HDL_TAP"TRUE"
BODY_TYPE"PLUMBING"
CDS_LIB"mstr_standard";
"B \NAC \NWC"2;
"S \NAC"
BN"6"143;
%"TAP"
"6","(-3150,2300)","0","mstr_standard","I50";
;
HDL_TAP"TRUE"
BODY_TYPE"PLUMBING"
CDS_LIB"mstr_standard";
"B \NAC \NWC"2;
"S \NAC"
BN"7"131;
%"TAP"
"6","(-3150,2250)","0","mstr_standard","I51";
;
HDL_TAP"TRUE"
BODY_TYPE"PLUMBING"
CDS_LIB"mstr_standard";
"B \NAC \NWC"2;
"S \NAC"
BN"4"174;
%"TAP"
"6","(-3150,2200)","0","mstr_standard","I52";
;
HDL_TAP"TRUE"
BODY_TYPE"PLUMBING"
CDS_LIB"mstr_standard";
"B \NAC \NWC"2;
"S \NAC"
BN"5"132;
%"TAP"
"6","(-3150,2150)","0","mstr_standard","I53";
;
HDL_TAP"TRUE"
BODY_TYPE"PLUMBING"
CDS_LIB"mstr_standard";
"B \NAC \NWC"2;
"S \NAC"
BN"2"133;
%"TAP"
"6","(-3150,2050)","0","mstr_standard","I54";
;
HDL_TAP"TRUE"
BODY_TYPE"PLUMBING"
CDS_LIB"mstr_standard";
"B \NAC \NWC"2;
"S \NAC"
BN"0"135;
%"TAP"
"6","(-3150,2100)","0","mstr_standard","I55";
;
HDL_TAP"TRUE"
BODY_TYPE"PLUMBING"
CDS_LIB"mstr_standard";
"B \NAC \NWC"2;
"S \NAC"
BN"3"134;
%"TAP"
"6","(-3150,2000)","0","mstr_standard","I56";
;
HDL_TAP"TRUE"
BODY_TYPE"PLUMBING"
CDS_LIB"mstr_standard";
"B \NAC \NWC"2;
"S \NAC"
BN"1"152;
END.
